# T6G (Grand Teton) — schematic netlist excerpt (pin names and nets, part order shuffled) for the footprints in the layout excerpt that follows; sources: Cadence DE-HDL packaged netlist, KiCad conversion of 04192023_DAF0TMB3IC0_F0TG_MB_C_brd_V02_OCP.brd

R1204  Q_RES  0 5% CHIP  pkg 0402LF  page 27 : A = FM_BIOS_USB_RECOVERY_R ; B = FM_BIOS_USB_RECOVERY
PC133  Q_CAP  0.22UF 16V 10% X7R  pkg 0402  page 213 : A = SW_PVDDCR_CPU0_P1_BOOT6_RC ; B = SW_PVDDCR_CPU0_P1_PH6

(kicad_pcb
	(version 20260206)
	(generator "pcbnew")
	(generator_version "10.0")
	(general
		(thickness 1.6)
		(legacy_teardrops no)
	)
	(paper "A4")
	(title_block
		(title "04192023_DAF0TMB3IC0_F0TG_MB_C_brd_V02_OCP.brd")
		(comment 1 "Grand Teton / footprints 4098-4099 of 8354")
	)
	(layers
		(0 "F.Cu" signal "TOP")
		(4 "In1.Cu" signal "GND")
		(6 "In2.Cu" signal "IN1")
		(8 "In3.Cu" signal "GND1")
		(10 "In4.Cu" signal "IN2")
		(12 "In5.Cu" signal "GND2")
		(14 "In6.Cu" signal "IN3")
		(16 "In7.Cu" signal "GND3")
		(18 "In8.Cu" signal "VCC")
		(20 "In9.Cu" signal "VCC1")
		(22 "In10.Cu" signal "GND4")
		(24 "In11.Cu" signal "IN4")
		(26 "In12.Cu" signal "GND5")
		(28 "In13.Cu" signal "IN5")
		(30 "In14.Cu" signal "GND6")
		(32 "In15.Cu" signal "IN6")
		(34 "In16.Cu" signal "GND7")
		(2 "B.Cu" signal "BOTTOM")
		(9 "F.Adhes" user "F.Adhesive")
		(11 "B.Adhes" user "B.Adhesive")
		(13 "F.Paste" user "Package Geometry/Pastemask Top")
		(15 "B.Paste" user "Package Geometry/Pastemask Bottom")
		(5 "F.SilkS" user "Ref Des/Silkscreen Top")
		(7 "B.SilkS" user "Ref Des/Silkscreen Bottom")
		(1 "F.Mask" user "Board Geometry/Soldermask Top")
		(3 "B.Mask" user "Board Geometry/Soldermask Bottom")
		(17 "Dwgs.User" user "User.Drawings")
		(19 "Cmts.User" user "User.Comments")
		(21 "Eco1.User" user "User.Eco1")
		(23 "Eco2.User" user "User.Eco2")
		(25 "Edge.Cuts" user "Board Geometry/Outline")
		(27 "Margin" user)
		(31 "F.CrtYd" user "Package Geometry/Place Bound Top")
		(29 "B.CrtYd" user "Package Geometry/Place Bound Bottom")
		(35 "F.Fab" user "Ref Des/Assembly Top")
		(33 "B.Fab" user "Ref Des/Assembly Bottom")
	)
	(footprint ""
		(layer "F.Cu")
		(at 368.130836 -323.466968 90)
		(property "Reference" "R1204"
			(at 0 0 90)
			(layer "F.SilkS")
			(hide yes)
			(effects
				(font
					(size 1.27 1.27)
				)
			)
		)
		(property "Value" ""
			(at 0 0 90)
			(layer "F.Fab")
			(effects
				(font
					(size 1.27 1.27)
				)
			)
		)
		(duplicate_pad_numbers_are_jumpers no)
		(fp_line
			(start 0.7874 -0.4064)
			(end 0.7874 0.4064)
			(stroke
				(width 0.1524)
				(type default)
			)
			(layer "F.SilkS")
		)
		(fp_line
			(start -0.7874 -0.4064)
			(end 0.7874 -0.4064)
			(stroke
				(width 0.1524)
				(type default)
			)
			(layer "F.SilkS")
		)
		(fp_line
			(start 0.7874 0.4064)
			(end -0.7874 0.4064)
			(stroke
				(width 0.1524)
				(type default)
			)
			(layer "F.SilkS")
		)
		(fp_line
			(start -0.7874 0.4064)
			(end -0.7874 -0.4064)
			(stroke
				(width 0.1524)
				(type default)
			)
			(layer "F.SilkS")
		)
		(fp_line
			(start -0.12065 -0.305054)
			(end -0.12065 -0.2794)
			(stroke
				(width 0.1)
				(type default)
			)
			(layer "F.Fab")
		)
		(fp_line
			(start -0.67945 -0.305054)
			(end -0.12065 -0.305054)
			(stroke
				(width 0.1)
				(type default)
			)
			(layer "F.Fab")
		)
		(fp_line
			(start 0.67945 -0.3048)
			(end 0.67945 0.3048)
			(stroke
				(width 0.1)
				(type default)
			)
			(layer "F.Fab")
		)
		(fp_line
			(start 0.12065 -0.3048)
			(end 0.67945 -0.3048)
			(stroke
				(width 0.1)
				(type default)
			)
			(layer "F.Fab")
		)
		(fp_line
			(start 0.12065 -0.2794)
			(end 0.12065 -0.3048)
			(stroke
				(width 0.1)
				(type default)
			)
			(layer "F.Fab")
		)
		(fp_line
			(start -0.12065 -0.2794)
			(end 0.12065 -0.2794)
			(stroke
				(width 0.1)
				(type default)
			)
			(layer "F.Fab")
		)
		(fp_line
			(start 0.120396 0.2794)
			(end -0.12065 0.2794)
			(stroke
				(width 0.1)
				(type default)
			)
			(layer "F.Fab")
		)
		(fp_line
			(start -0.12065 0.2794)
			(end -0.12065 0.3048)
			(stroke
				(width 0.1)
				(type default)
			)
			(layer "F.Fab")
		)
		(fp_line
			(start 0.67945 0.3048)
			(end 0.120396 0.3048)
			(stroke
				(width 0.1)
				(type default)
			)
			(layer "F.Fab")
		)
		(fp_line
			(start 0.120396 0.3048)
			(end 0.120396 0.2794)
			(stroke
				(width 0.1)
				(type default)
			)
			(layer "F.Fab")
		)
		(fp_line
			(start -0.12065 0.3048)
			(end -0.67945 0.3048)
			(stroke
				(width 0.1)
				(type default)
			)
			(layer "F.Fab")
		)
		(fp_line
			(start -0.67945 0.3048)
			(end -0.67945 -0.305054)
			(stroke
				(width 0.1)
				(type default)
			)
			(layer "F.Fab")
		)
		(pad "1" smd circle
			(at -0.40005 0 90)
			(size 0 0)
			(layers "F.Cu" "F.Mask" "F.Paste")
			(net "FM_BIOS_USB_RECOVERY_R")
		)
		(pad "2" smd circle
			(at 0.40005 0 90)
			(size 0 0)
			(layers "F.Cu" "F.Mask" "F.Paste")
			(net "FM_BIOS_USB_RECOVERY")
		)
	)
	(footprint ""
		(layer "F.Cu")
		(at 63.861696 -164.276786 90)
		(property "Reference" "PC133"
			(at 0 0 90)
			(layer "F.SilkS")
			(hide yes)
			(effects
				(font
					(size 1.27 1.27)
				)
			)
		)
		(property "Value" ""
			(at 0 0 90)
			(layer "F.Fab")
			(effects
				(font
					(size 1.27 1.27)
				)
			)
		)
		(duplicate_pad_numbers_are_jumpers no)
		(fp_line
			(start 0.7874 -0.4064)
			(end 0.7874 0.4064)
			(stroke
				(width 0.1524)
				(type default)
			)
			(layer "F.SilkS")
		)
		(fp_line
			(start -0.7874 -0.4064)
			(end 0.7874 -0.4064)
			(stroke
				(width 0.1524)
				(type default)
			)
			(layer "F.SilkS")
		)
		(fp_line
			(start 0.7874 0.4064)
			(end -0.7874 0.4064)
			(stroke
				(width 0.1524)
				(type default)
			)
			(layer "F.SilkS")
		)
		(fp_line
			(start -0.7874 0.4064)
			(end -0.7874 -0.4064)
			(stroke
				(width 0.1524)
				(type default)
			)
			(layer "F.SilkS")
		)
		(fp_line
			(start -0.12065 -0.305054)
			(end -0.12065 -0.2794)
			(stroke
				(width 0.1)
				(type default)
			)
			(layer "F.Fab")
		)
		(fp_line
			(start -0.67945 -0.305054)
			(end -0.12065 -0.305054)
			(stroke
				(width 0.1)
				(type default)
			)
			(layer "F.Fab")
		)
		(fp_line
			(start 0.67945 -0.3048)
			(end 0.67945 0.3048)
			(stroke
				(width 0.1)
				(type default)
			)
			(layer "F.Fab")
		)
		(fp_line
			(start 0.12065 -0.3048)
			(end 0.67945 -0.3048)
			(stroke
				(width 0.1)
				(type default)
			)
			(layer "F.Fab")
		)
		(fp_line
			(start 0.12065 -0.2794)
			(end 0.12065 -0.3048)
			(stroke
				(width 0.1)
				(type default)
			)
			(layer "F.Fab")
		)
		(fp_line
			(start -0.12065 -0.2794)
			(end 0.12065 -0.2794)
			(stroke
				(width 0.1)
				(type default)
			)
			(layer "F.Fab")
		)
		(fp_line
			(start 0.120396 0.2794)
			(end -0.12065 0.2794)
			(stroke
				(width 0.1)
				(type default)
			)
			(layer "F.Fab")
		)
		(fp_line
			(start -0.12065 0.2794)
			(end -0.12065 0.3048)
			(stroke
				(width 0.1)
				(type default)
			)
			(layer "F.Fab")
		)
		(fp_line
			(start 0.67945 0.3048)
			(end 0.120396 0.3048)
			(stroke
				(width 0.1)
				(type default)
			)
			(layer "F.Fab")
		)
		(fp_line
			(start 0.120396 0.3048)
			(end 0.120396 0.2794)
			(stroke
				(width 0.1)
				(type default)
			)
			(layer "F.Fab")
		)
		(fp_line
			(start -0.12065 0.3048)
			(end -0.67945 0.3048)
			(stroke
				(width 0.1)
				(type default)
			)
			(layer "F.Fab")
		)
		(fp_line
			(start -0.67945 0.3048)
			(end -0.67945 -0.305054)
			(stroke
				(width 0.1)
				(type default)
			)
			(layer "F.Fab")
		)
		(pad "1" smd circle
			(at -0.40005 0 90)
			(size 0 0)
			(layers "F.Cu" "F.Mask" "F.Paste")
			(net "SW_PVDDCR_CPU0_P1_BOOT6_RC")
		)
		(pad "2" smd circle
			(at 0.40005 0 90)
			(size 0 0)
			(layers "F.Cu" "F.Mask" "F.Paste")
			(net "SW_PVDDCR_CPU0_P1_PH6")
		)
	)
)
